# BASEBOARD_FAB2 (Tioga Pass) — schematic netlist excerpt (pin names and nets, part order shuffled) for the footprints in the layout excerpt that follows; sources: Cadence DE-HDL packaged netlist, KiCad conversion of Wiwynn_Tioga_Pass_MB.brd

U1M6  74CBTLV1G125  IC  pkg SMLF  page 113
  OE_N  = FM_CPU0_AND_CPU1_MCP_PRES
  A  = JTAG_MCP_CPU0_TDO
  B  = JTAG_MCP_CPU1_TDI

R1M25  RES  10.0K 1% CHIP  pkg 0402  page 176 : A = FM_USB_P0_EN_R_N ; B = GND
C8U2  CAP_A  47UF 4V 20% X5R  pkg 0603V  page 225 : A = PVDDQ_GHJ ; B = GND

(kicad_pcb
	(version 20260206)
	(generator "pcbnew")
	(generator_version "10.0")
	(general
		(thickness 1.6)
		(legacy_teardrops no)
	)
	(paper "A4")
	(title_block
		(title "Wiwynn_Tioga_Pass_MB.brd")
		(comment 1 "Tioga Pass / footprints 3890-3892 of 4770")
	)
	(layers
		(0 "F.Cu" signal "TOP")
		(4 "In1.Cu" signal "L2GND")
		(6 "In2.Cu" signal "L3")
		(8 "In3.Cu" signal "L4GND")
		(10 "In4.Cu" signal "L5")
		(12 "In5.Cu" signal "L6GND")
		(14 "In6.Cu" signal "L7VCC")
		(16 "In7.Cu" signal "L8VCC")
		(18 "In8.Cu" signal "L9GND")
		(20 "In9.Cu" signal "L10")
		(22 "In10.Cu" signal "L11GND")
		(24 "In11.Cu" signal "L12")
		(26 "In12.Cu" signal "L13GND")
		(2 "B.Cu" signal "BOTTOM")
		(9 "F.Adhes" user "F.Adhesive")
		(11 "B.Adhes" user "B.Adhesive")
		(13 "F.Paste" user "Package Geometry/Pastemask Top")
		(15 "B.Paste" user "Package Geometry/Pastemask Bottom")
		(5 "F.SilkS" user "Ref Des/Silkscreen Top")
		(7 "B.SilkS" user "Ref Des/Silkscreen Bottom")
		(1 "F.Mask" user "Board Geometry/Soldermask Top")
		(3 "B.Mask" user "Board Geometry/Soldermask Bottom")
		(17 "Dwgs.User" user "User.Drawings")
		(19 "Cmts.User" user "User.Comments")
		(21 "Eco1.User" user "User.Eco1")
		(23 "Eco2.User" user "User.Eco2")
		(25 "Edge.Cuts" user "Board Geometry/Outline")
		(27 "Margin" user)
		(31 "F.CrtYd" user "Package Geometry/Place Bound Top")
		(29 "B.CrtYd" user "Package Geometry/Place Bound Bottom")
		(35 "F.Fab" user "Ref Des/Assembly Top")
		(33 "B.Fab" user "Ref Des/Assembly Bottom")
	)
	(footprint ""
		(layer "B.Cu")
		(at 468.884 -127.635 180)
		(property "Reference" "R1M25"
			(at 0 0 0)
			(layer "B.SilkS")
			(hide yes)
			(effects
				(font
					(size 1.27 1.27)
				)
				(justify mirror)
			)
		)
		(property "Value" ""
			(at 0 0 0)
			(layer "B.Fab")
			(effects
				(font
					(size 1.27 1.27)
				)
				(justify mirror)
			)
		)
		(duplicate_pad_numbers_are_jumpers no)
		(fp_poly
			(pts
				(xy 0.2794 -0.1016) (xy -0.2794 -0.1016) (xy -0.2794 0.9906) (xy 0.2794 0.9906)
			)
			(stroke
				(width 0)
				(type default)
			)
			(fill no)
			(layer "B.CrtYd")
		)
		(fp_line
			(start 0.2794 0.9906)
			(end -0.2794 0.9906)
			(stroke
				(width 0.1)
				(type default)
			)
			(layer "B.Fab")
		)
		(fp_line
			(start 0.2794 -0.1016)
			(end 0.2794 0.9906)
			(stroke
				(width 0.1)
				(type default)
			)
			(layer "B.Fab")
		)
		(fp_line
			(start -0.2794 0.9906)
			(end -0.2794 -0.1016)
			(stroke
				(width 0.1)
				(type default)
			)
			(layer "B.Fab")
		)
		(fp_line
			(start -0.2794 -0.1016)
			(end 0.2794 -0.1016)
			(stroke
				(width 0.1)
				(type default)
			)
			(layer "B.Fab")
		)
		(pad "1" smd rect
			(at 0 0)
			(size 0.508 0.508)
			(layers "B.Cu" "B.Mask" "B.Paste")
			(net "FM_USB_P0_EN_R_N")
		)
		(pad "2" smd rect
			(at 0 0.889)
			(size 0.508 0.508)
			(layers "B.Cu" "B.Mask" "B.Paste")
			(net "GND")
		)
		(zone
			(layer "B.Cu")
			(hatch none 0.5)
			(connect_pads
				(clearance 0)
			)
			(min_thickness 0.25)
			(keepout
				(tracks not_allowed)
				(vias allowed)
				(pads allowed)
				(copperpour not_allowed)
				(footprints allowed)
			)
			(placement
				(enabled no)
				(sheetname "")
			)
			(fill
				(thermal_gap 0.5)
				(thermal_bridge_width 0.5)
				(island_removal_mode 0)
			)
			(polygon
				(pts
					(xy 468.63 -128.27) (xy 469.138 -128.27) (xy 469.138 -127.889) (xy 468.63 -127.889)
				)
			)
		)
		(zone
			(layer "B.Cu")
			(hatch none 0.5)
			(connect_pads
				(clearance 0)
			)
			(min_thickness 0.25)
			(keepout
				(tracks allowed)
				(vias not_allowed)
				(pads allowed)
				(copperpour not_allowed)
				(footprints allowed)
			)
			(placement
				(enabled no)
				(sheetname "")
			)
			(fill
				(thermal_gap 0.5)
				(thermal_bridge_width 0.5)
				(island_removal_mode 0)
			)
			(polygon
				(pts
					(xy 468.63 -127.889) (xy 469.138 -127.889) (xy 469.138 -128.27) (xy 468.63 -128.27)
				)
			)
		)
	)
	(footprint ""
		(layer "B.Cu")
		(at 104.5591 -8.1534 90)
		(property "Reference" "C8U2"
			(at -1.848866 0.752348 90)
			(unlocked yes)
			(layer "B.SilkS")
			(effects
				(font
					(size 1.27 0.9652)
					(thickness 0.1524)
				)
				(justify mirror)
			)
		)
		(property "Value" ""
			(at 0 0 90)
			(layer "B.Fab")
			(effects
				(font
					(size 1.27 1.27)
				)
				(justify mirror)
			)
		)
		(duplicate_pad_numbers_are_jumpers no)
		(fp_rect
			(start 0.500126 1.598422)
			(end -0.500126 -0.201422)
			(stroke
				(width 0)
				(type default)
			)
			(fill no)
			(layer "B.CrtYd")
		)
		(fp_line
			(start 0.500126 -0.201422)
			(end -0.500126 -0.201422)
			(stroke
				(width 0.1)
				(type default)
			)
			(layer "B.Fab")
		)
		(fp_line
			(start -0.500126 -0.201422)
			(end -0.500126 1.598422)
			(stroke
				(width 0.1)
				(type default)
			)
			(layer "B.Fab")
		)
		(fp_line
			(start 0.500126 1.598422)
			(end 0.500126 -0.201422)
			(stroke
				(width 0.1)
				(type default)
			)
			(layer "B.Fab")
		)
		(fp_line
			(start -0.500126 1.598422)
			(end 0.500126 1.598422)
			(stroke
				(width 0.1)
				(type default)
			)
			(layer "B.Fab")
		)
		(pad "1" smd rect
			(at 0 0)
			(size 0.889 0.9906)
			(layers "B.Cu" "B.Mask" "B.Paste")
			(net "PVDDQ_GHJ")
		)
		(pad "2" smd rect
			(at 0 1.397)
			(size 0.889 0.9906)
			(layers "B.Cu" "B.Mask" "B.Paste")
			(net "GND")
		)
		(zone
			(layer "B.Cu")
			(hatch none 0.5)
			(connect_pads
				(clearance 0)
			)
			(min_thickness 0.25)
			(keepout
				(tracks allowed)
				(vias not_allowed)
				(pads allowed)
				(copperpour not_allowed)
				(footprints allowed)
			)
			(placement
				(enabled no)
				(sheetname "")
			)
			(fill
				(thermal_gap 0.5)
				(thermal_bridge_width 0.5)
				(island_removal_mode 0)
			)
			(polygon
				(pts
					(xy 105.5116 -8.6487) (xy 105.0036 -8.6487) (xy 105.0036 -7.6581) (xy 105.5116 -7.6581)
				)
			)
		)
		(zone
			(layer "B.Cu")
			(hatch none 0.5)
			(connect_pads
				(clearance 0)
			)
			(min_thickness 0.25)
			(keepout
				(tracks not_allowed)
				(vias allowed)
				(pads allowed)
				(copperpour not_allowed)
				(footprints allowed)
			)
			(placement
				(enabled no)
				(sheetname "")
			)
			(fill
				(thermal_gap 0.5)
				(thermal_bridge_width 0.5)
				(island_removal_mode 0)
			)
			(polygon
				(pts
					(xy 105.5116 -8.6487) (xy 105.0036 -8.6487) (xy 105.0036 -7.6581) (xy 105.5116 -7.6581)
				)
			)
		)
	)
	(footprint ""
		(layer "B.Cu")
		(at 499.62816 -128.52654 -90)
		(property "Reference" "U1M6"
			(at -1.6383 -1.23317 270)
			(unlocked yes)
			(layer "B.SilkS")
			(effects
				(font
					(size 0.7874 0.5842)
					(thickness 0.1524)
				)
				(justify left mirror)
			)
		)
		(property "Value" ""
			(at 0 0 90)
			(layer "B.Fab")
			(effects
				(font
					(size 1.27 1.27)
				)
				(justify mirror)
			)
		)
		(duplicate_pad_numbers_are_jumpers no)
		(fp_circle
			(center 0.4699 -0.8382)
			(end 0.4699 -0.9652)
			(stroke
				(width 0.254)
				(type default)
			)
			(fill no)
			(layer "B.SilkS")
		)
		(fp_poly
			(pts
				(xy -0.21463 -0.450088) (xy -1.56337 -0.450088) (xy -1.56337 1.75006) (xy -0.21463 1.75006)
			)
			(stroke
				(width 0)
				(type default)
			)
			(fill no)
			(layer "B.CrtYd")
		)
		(fp_line
			(start -1.56337 1.75006)
			(end -0.21463 1.75006)
			(stroke
				(width 0.1)
				(type default)
			)
			(layer "B.Fab")
		)
		(fp_line
			(start -0.21463 1.75006)
			(end -0.21463 -0.450088)
			(stroke
				(width 0.1)
				(type default)
			)
			(layer "B.Fab")
		)
		(fp_line
			(start -1.56337 -0.450088)
			(end -1.56337 1.75006)
			(stroke
				(width 0.1)
				(type default)
			)
			(layer "B.Fab")
		)
		(fp_line
			(start -0.21463 -0.450088)
			(end -1.56337 -0.450088)
			(stroke
				(width 0.1)
				(type default)
			)
			(layer "B.Fab")
		)
		(fp_circle
			(center 0.4699 -0.8382)
			(end 0.4699 -0.9652)
			(stroke
				(width 0.254)
				(type default)
			)
			(fill no)
			(layer "B.Fab")
		)
		(pad "1" smd rect
			(at 0 0 90)
			(size 1.016 0.381)
			(layers "B.Cu" "B.Mask" "B.Paste")
			(net "FM_CPU0_AND_CPU1_MCP_PRES")
		)
		(pad "2" smd rect
			(at 0 0.649986 90)
			(size 1.016 0.381)
			(layers "B.Cu" "B.Mask" "B.Paste")
			(net "JTAG_MCP_CPU0_TDO")
		)
		(pad "3" smd rect
			(at 0 1.299972 90)
			(size 1.016 0.381)
			(layers "B.Cu" "B.Mask" "B.Paste")
			(net "GND")
		)
		(pad "4" smd rect
			(at -1.778 1.299972 90)
			(size 1.016 0.381)
			(layers "B.Cu" "B.Mask" "B.Paste")
			(net "JTAG_MCP_CPU1_TDI")
		)
		(pad "5" smd rect
			(at -1.778 0 90)
			(size 1.016 0.381)
			(layers "B.Cu" "B.Mask" "B.Paste")
			(net "P3V3_STBY")
		)
	)
)
